(kicad_pcb
	(version 20241229)
	(generator "pcbnew")
	(generator_version "9.0")
	(general
		(thickness 1.711)
		(legacy_teardrops no)
	)
	(paper "A4")
	(title_block
		(title "Antmicro Baseboard for Jetson AGX Thor")
		(date "2026-02-18")
		(rev "1.1.0")
		(company "Antmicro Ltd")
		(comment 1 "www.antmicro.com")
		(comment 9 "footprints 346-350 of 1170")
	)
	(layers
		(0 "F.Cu" signal)
		(4 "In1.Cu" signal)
		(6 "In2.Cu" signal)
		(8 "In3.Cu" signal)
		(10 "In4.Cu" jumper)
		(12 "In5.Cu" signal)
		(14 "In6.Cu" signal)
		(16 "In7.Cu" signal)
		(18 "In8.Cu" signal)
		(2 "B.Cu" signal)
		(9 "F.Adhes" user "F.Adhesive")
		(11 "B.Adhes" user "B.Adhesive")
		(13 "F.Paste" user)
		(15 "B.Paste" user)
		(5 "F.SilkS" user "F.Silkscreen")
		(7 "B.SilkS" user "B.Silkscreen")
		(1 "F.Mask" user)
		(3 "B.Mask" user)
		(17 "Dwgs.User" user "User.Drawings")
		(19 "Cmts.User" user "User.Comments")
		(21 "Eco1.User" user "User.Eco1")
		(23 "Eco2.User" user "User.Eco2")
		(25 "Edge.Cuts" user)
		(27 "Margin" user)
		(31 "F.CrtYd" user "F.Courtyard")
		(29 "B.CrtYd" user "B.Courtyard")
		(35 "F.Fab" user)
		(33 "B.Fab" user)
	)
	(footprint "antmicro-footprints:L_Bourns-SRP6050CA"
		(layer "F.Cu")
		(at 178.86 118.426 180)
		(property "Reference" "L1"
			(at -3.629468 0.626 90)
			(layer "F.SilkS")
			(effects
				(font
					(size 0.7 0.7)
					(thickness 0.15)
				)
				(justify right top)
			)
		)
		(property "Value" "L_1u_20A_Bourns-SRP6050CA"
			(at -0.025 4.85 0)
			(layer "F.Fab")
			(effects
				(font
					(size 0.7 0.7)
					(thickness 0.15)
				)
				(justify right top)
			)
		)
		(property "Datasheet" "https://www.bourns.com/docs/Product-Datasheets/SRP6050CA.pdf"
			(at 0 0 0)
			(layer "F.Fab")
			(hide yes)
			(effects
				(font
					(size 1.27 1.27)
					(thickness 0.15)
				)
			)
		)
		(property "Description" "Power Inductor (SMT), 1 µH, 20 A, Shielded, 23 A, SRP6050CA"
			(at 0 0 0)
			(layer "F.Fab")
			(hide yes)
			(effects
				(font
					(size 1.27 1.27)
					(thickness 0.15)
				)
			)
		)
		(property "Val" "1u/20A"
			(at 0 0 180)
			(unlocked yes)
			(layer "F.Fab")
			(hide yes)
			(effects
				(font
					(size 1 1)
					(thickness 0.15)
				)
			)
		)
		(property "Manufacturer" "Bourns"
			(at 0 0 180)
			(unlocked yes)
			(layer "F.Fab")
			(hide yes)
			(effects
				(font
					(size 1 1)
					(thickness 0.15)
				)
			)
		)
		(property "MPN" "SRP6050CA-1R0M"
			(at 0 0 180)
			(unlocked yes)
			(layer "F.Fab")
			(hide yes)
			(effects
				(font
					(size 1 1)
					(thickness 0.15)
				)
			)
		)
		(property "ISat" "23 A"
			(at 0 0 180)
			(unlocked yes)
			(layer "F.Fab")
			(hide yes)
			(effects
				(font
					(size 1 1)
					(thickness 0.15)
				)
			)
		)
		(property "IMax" "20 A"
			(at 0 0 180)
			(unlocked yes)
			(layer "F.Fab")
			(hide yes)
			(effects
				(font
					(size 1 1)
					(thickness 0.15)
				)
			)
		)
		(property "Size" "6.6x6.4"
			(at 0 0 180)
			(unlocked yes)
			(layer "F.Fab")
			(hide yes)
			(effects
				(font
					(size 1 1)
					(thickness 0.15)
				)
			)
		)
		(property "Author" "Antmicro"
			(at 0 0 180)
			(unlocked yes)
			(layer "F.Fab")
			(hide yes)
			(effects
				(font
					(size 1 1)
					(thickness 0.15)
				)
			)
		)
		(property "License" "Apache-2.0"
			(at 0 0 180)
			(unlocked yes)
			(layer "F.Fab")
			(hide yes)
			(effects
				(font
					(size 1 1)
					(thickness 0.15)
				)
			)
		)
		(sheetname "/DCDC/")
		(sheetfile "dcdc.kicad_sch")
		(attr smd)
		(fp_line
			(start 3.2 3.298)
			(end -3.2 3.298)
			(stroke
				(width 0.15)
				(type solid)
			)
			(layer "F.SilkS")
		)
		(fp_line
			(start 3.2 -3.301)
			(end 3.2 3.298)
			(stroke
				(width 0.15)
				(type solid)
			)
			(layer "F.SilkS")
		)
		(fp_line
			(start -3.2 -3.301)
			(end 3.2 -3.301)
			(stroke
				(width 0.15)
				(type solid)
			)
			(layer "F.SilkS")
		)
		(fp_line
			(start -3.2 -3.301)
			(end -3.2 3.298)
			(stroke
				(width 0.15)
				(type solid)
			)
			(layer "F.SilkS")
		)
		(fp_rect
			(start -3.45 -3.55)
			(end 3.45 3.55)
			(stroke
				(width 0.05)
				(type solid)
			)
			(fill no)
			(layer "F.CrtYd")
		)
		(fp_rect
			(start -3.202 -3.301)
			(end 3.2 3.298)
			(stroke
				(width 0.15)
				(type solid)
			)
			(fill no)
			(layer "F.Fab")
		)
		(fp_text user "Author: Antmicro"
			(at -3.45 9.25 0)
			(layer "F.Fab")
			(effects
				(font
					(size 0.7 0.7)
					(thickness 0.15)
				)
				(justify right top)
			)
		)
		(fp_text user "${REFERENCE}"
			(at -3.45 6.85 0)
			(layer "F.Fab")
			(effects
				(font
					(size 0.7 0.7)
					(thickness 0.15)
				)
				(justify right top)
			)
		)
		(fp_text user "License: Apache-2.0"
			(at -3.45 8.05 0)
			(layer "F.Fab")
			(effects
				(font
					(size 0.7 0.7)
					(thickness 0.15)
				)
				(justify right top)
			)
		)
		(pad "1" smd roundrect
			(at -2.025 0 180)
			(size 1.55 5.6)
			(layers "F.Cu" "F.Mask" "F.Paste")
			(roundrect_rratio 0.1)
			(net 1181 "/DCDC/5V_SW")
			(pintype "passive")
		)
		(pad "2" smd roundrect
			(at 2.025 0 180)
			(size 1.55 5.6)
			(layers "F.Cu" "F.Mask" "F.Paste")
			(roundrect_rratio 0.1)
			(net 253 "/DCDC/5V_OUT")
			(pintype "passive")
		)
	)
	(footprint "antmicro-footprints:R_0402_1005Metric"
		(layer "F.Cu")
		(at 182.829468 67.72 90)
		(descr "Resistor SMD 0402")
		(tags "resistor SMD 0402")
		(property "Reference" "R94"
			(at -0.75 2.54 90)
			(layer "F.SilkS")
			(effects
				(font
					(size 0.7 0.7)
					(thickness 0.15)
				)
				(justify left bottom)
			)
		)
		(property "Value" "R_330k_0402"
			(at -1.011843 1.772047 90)
			(layer "F.Fab")
			(effects
				(font
					(size 0.7 0.7)
					(thickness 0.15)
				)
				(justify left bottom)
			)
		)
		(property "Datasheet" "https://www.bourns.com/docs/product-datasheets/cr.pdf"
			(at 0 0 90)
			(layer "F.Fab")
			(hide yes)
			(effects
				(font
					(size 1.27 1.27)
					(thickness 0.15)
				)
			)
		)
		(property "Description" "SMD Chip Resistor"
			(at 0 0 90)
			(layer "F.Fab")
			(hide yes)
			(effects
				(font
					(size 1.27 1.27)
					(thickness 0.15)
				)
			)
		)
		(property "MPN" "CR0402-FX-3303GLF"
			(at 0 0 90)
			(unlocked yes)
			(layer "F.Fab")
			(hide yes)
			(effects
				(font
					(size 1 1)
					(thickness 0.15)
				)
			)
		)
		(property "Manufacturer" "Bourns"
			(at 0 0 90)
			(unlocked yes)
			(layer "F.Fab")
			(hide yes)
			(effects
				(font
					(size 1 1)
					(thickness 0.15)
				)
			)
		)
		(property "License" "Apache-2.0"
			(at 0 0 90)
			(unlocked yes)
			(layer "F.Fab")
			(hide yes)
			(effects
				(font
					(size 1 1)
					(thickness 0.15)
				)
			)
		)
		(property "Author" "Antmicro"
			(at 0 0 90)
			(unlocked yes)
			(layer "F.Fab")
			(hide yes)
			(effects
				(font
					(size 1 1)
					(thickness 0.15)
				)
			)
		)
		(property "Val" "330k"
			(at 0 0 90)
			(unlocked yes)
			(layer "F.Fab")
			(hide yes)
			(effects
				(font
					(size 1 1)
					(thickness 0.15)
				)
			)
		)
		(property "Tolerance" "1%"
			(at 0 0 90)
			(unlocked yes)
			(layer "F.Fab")
			(hide yes)
			(effects
				(font
					(size 1 1)
					(thickness 0.15)
				)
			)
		)
		(component_classes
			(class "DCDC_20V")
		)
		(sheetname "/DCDC/")
		(sheetfile "dcdc.kicad_sch")
		(attr smd)
		(fp_rect
			(start -0.925 -0.47)
			(end 0.925 0.47)
			(stroke
				(width 0.05)
				(type default)
			)
			(fill no)
			(layer "F.CrtYd")
		)
		(fp_rect
			(start -0.5 -0.25)
			(end 0.5 0.25)
			(stroke
				(width 0.15)
				(type solid)
			)
			(fill no)
			(layer "F.Fab")
		)
		(fp_text user "License: Apache-2.0"
			(at -0.95 5.169 90)
			(layer "F.Fab")
			(effects
				(font
					(size 0.7 0.7)
					(thickness 0.15)
				)
				(justify left bottom)
			)
		)
		(fp_text user "Author: Antmicro"
			(at -0.95 4.169 90)
			(layer "F.Fab")
			(effects
				(font
					(size 0.7 0.7)
					(thickness 0.15)
				)
				(justify left bottom)
			)
		)
		(fp_text user "${REFERENCE}"
			(at -0.95 3.168 90)
			(layer "F.Fab")
			(effects
				(font
					(size 0.7 0.7)
					(thickness 0.15)
				)
				(justify left bottom)
			)
		)
		(pad "1" smd roundrect
			(at -0.48 0 90)
			(size 0.59 0.64)
			(layers "F.Cu" "F.Mask" "F.Paste")
			(roundrect_rratio 0.25)
			(net 1220 "/DCDC/20V_FB")
			(pintype "passive")
		)
		(pad "2" smd roundrect
			(at 0.48 0 90)
			(size 0.59 0.64)
			(layers "F.Cu" "F.Mask" "F.Paste")
			(roundrect_rratio 0.25)
			(net 1105 "/DCDC/20V_OUT")
			(pintype "passive")
		)
	)
	(footprint "antmicro-footprints:C_0402_1005Metric"
		(layer "F.Cu")
		(at 91.1 94.5)
		(descr "Capacitor SMD 0402")
		(tags "capacitor SMD 0402")
		(property "Reference" "C346"
			(at 1.1 0.500001 0)
			(layer "F.SilkS")
			(effects
				(font
					(size 0.7 0.7)
					(thickness 0.15)
				)
				(justify left bottom)
			)
		)
		(property "Value" "C_100n_0402"
			(at -1.022927 2.155213 0)
			(layer "F.Fab")
			(effects
				(font
					(size 0.7 0.7)
					(thickness 0.15)
				)
				(justify left bottom)
			)
		)
		(property "Datasheet" "https://www.murata.com/products/productdetail?partno=GRM155R61H104KE14%23"
			(at 0 0 0)
			(layer "F.Fab")
			(hide yes)
			(effects
				(font
					(size 1.27 1.27)
					(thickness 0.15)
				)
			)
		)
		(property "Description" "SMD Multilayer Ceramic Capacitor, 0.1 µF, 50 V, 0402 [1005 Metric], ± 10%, X5R, GRM Series"
			(at 0 0 0)
			(layer "F.Fab")
			(hide yes)
			(effects
				(font
					(size 1.27 1.27)
					(thickness 0.15)
				)
			)
		)
		(property "Manufacturer" "Murata"
			(at 0 0 0)
			(unlocked yes)
			(layer "F.Fab")
			(hide yes)
			(effects
				(font
					(size 1 1)
					(thickness 0.15)
				)
			)
		)
		(property "MPN" "GRM155R61H104KE14D"
			(at 0 0 0)
			(unlocked yes)
			(layer "F.Fab")
			(hide yes)
			(effects
				(font
					(size 1 1)
					(thickness 0.15)
				)
			)
		)
		(property "Val" "100n"
			(at 0 0 0)
			(unlocked yes)
			(layer "F.Fab")
			(hide yes)
			(effects
				(font
					(size 1 1)
					(thickness 0.15)
				)
			)
		)
		(property "License" "Apache-2.0"
			(at 0 0 0)
			(unlocked yes)
			(layer "F.Fab")
			(hide yes)
			(effects
				(font
					(size 1 1)
					(thickness 0.15)
				)
			)
		)
		(property "Author" "Antmicro"
			(at 0 0 0)
			(unlocked yes)
			(layer "F.Fab")
			(hide yes)
			(effects
				(font
					(size 1 1)
					(thickness 0.15)
				)
			)
		)
		(property "Voltage" "50V"
			(at 0 0 0)
			(unlocked yes)
			(layer "F.Fab")
			(hide yes)
			(effects
				(font
					(size 1 1)
					(thickness 0.15)
				)
			)
		)
		(property "Dielectric" "X5R"
			(at 0 0 0)
			(unlocked yes)
			(layer "F.Fab")
			(hide yes)
			(effects
				(font
					(size 1 1)
					(thickness 0.15)
				)
			)
		)
		(sheetname "/SoM_IO2/")
		(sheetfile "som_io2.kicad_sch")
		(attr smd)
		(fp_rect
			(start -0.925 -0.47)
			(end 0.925 0.47)
			(stroke
				(width 0.05)
				(type default)
			)
			(fill no)
			(layer "F.CrtYd")
		)
		(fp_line
			(start -0.494 -0.25)
			(end 0.504 -0.25)
			(stroke
				(width 0.15)
				(type solid)
			)
			(layer "F.Fab")
		)
		(fp_line
			(start -0.494 0.248)
			(end -0.494 -0.25)
			(stroke
				(width 0.15)
				(type solid)
			)
			(layer "F.Fab")
		)
		(fp_line
			(start 0.504 -0.25)
			(end 0.504 0.248)
			(stroke
				(width 0.15)
				(type solid)
			)
			(layer "F.Fab")
		)
		(fp_line
			(start 0.504 0.248)
			(end -0.494 0.248)
			(stroke
				(width 0.15)
				(type solid)
			)
			(layer "F.Fab")
		)
		(fp_text user "Author: Antmicro"
			(at -0.939 3.399 0)
			(layer "F.Fab")
			(effects
				(font
					(size 0.7 0.7)
					(thickness 0.15)
				)
				(justify left bottom)
			)
		)
		(fp_text user "${REFERENCE}"
			(at -0.939 4.599 0)
			(layer "F.Fab")
			(effects
				(font
					(size 0.7 0.7)
					(thickness 0.15)
				)
				(justify left bottom)
			)
		)
		(fp_text user "License: Apache-2.0"
			(at -0.939 5.799 0)
			(layer "F.Fab")
			(effects
				(font
					(size 0.7 0.7)
					(thickness 0.15)
				)
				(justify left bottom)
			)
		)
		(pad "1" smd roundrect
			(at -0.48 0)
			(size 0.59 0.64)
			(layers "F.Cu" "F.Mask" "F.Paste")
			(roundrect_rratio 0.25)
			(net 593 "/Expansion connector/DP3.TX2+")
			(pintype "passive")
		)
		(pad "2" smd roundrect
			(at 0.48 0)
			(size 0.59 0.64)
			(layers "F.Cu" "F.Mask" "F.Paste")
			(roundrect_rratio 0.25)
			(net 1266 "/SoM_IO2/DP3.TX2_C+")
			(pintype "passive")
		)
	)
	(footprint "antmicro-footprints:R_0402_1005Metric"
		(layer "F.Cu")
		(at 61.6 63.2)
		(descr "Resistor SMD 0402")
		(tags "resistor SMD 0402")
		(property "Reference" "R160"
			(at -1.4 3.6 0)
			(layer "F.SilkS")
			(effects
				(font
					(size 0.7 0.7)
					(thickness 0.15)
				)
				(justify left bottom)
			)
		)
		(property "Value" "R_0R_0402"
			(at -1.011843 1.772046 0)
			(layer "F.Fab")
			(effects
				(font
					(size 0.7 0.7)
					(thickness 0.15)
				)
				(justify left bottom)
			)
		)
		(property "Datasheet" "https://industrial.panasonic.com/cdbs/www-data/pdf/RDA0000/AOA0000C301.pdf"
			(at 0 0 0)
			(layer "F.Fab")
			(hide yes)
			(effects
				(font
					(size 1.27 1.27)
					(thickness 0.15)
				)
			)
		)
		(property "Description" "SMD Chip Resistor, Jumper, 0 ohm, 100 mW, 0402 [1005 Metric], Thick Film, General Purpose"
			(at 0 0 0)
			(layer "F.Fab")
			(hide yes)
			(effects
				(font
					(size 1.27 1.27)
					(thickness 0.15)
				)
			)
		)
		(property "Manufacturer" "Panasonic"
			(at 0 0 0)
			(unlocked yes)
			(layer "F.Fab")
			(hide yes)
			(effects
				(font
					(size 1 1)
					(thickness 0.15)
				)
			)
		)
		(property "MPN" "ERJ2GE0R00X"
			(at 0 0 0)
			(unlocked yes)
			(layer "F.Fab")
			(hide yes)
			(effects
				(font
					(size 1 1)
					(thickness 0.15)
				)
			)
		)
		(property "Val" "0R"
			(at 0 0 0)
			(unlocked yes)
			(layer "F.Fab")
			(hide yes)
			(effects
				(font
					(size 1 1)
					(thickness 0.15)
				)
			)
		)
		(property "License" "Apache-2.0"
			(at 0 0 0)
			(unlocked yes)
			(layer "F.Fab")
			(hide yes)
			(effects
				(font
					(size 1 1)
					(thickness 0.15)
				)
			)
		)
		(property "Author" "Antmicro"
			(at 0 0 0)
			(unlocked yes)
			(layer "F.Fab")
			(hide yes)
			(effects
				(font
					(size 1 1)
					(thickness 0.15)
				)
			)
		)
		(property "Tolerance" "~"
			(at 0 0 0)
			(unlocked yes)
			(layer "F.Fab")
			(hide yes)
			(effects
				(font
					(size 1 1)
					(thickness 0.15)
				)
			)
		)
		(property "Current" "1A"
			(at 0 0 0)
			(unlocked yes)
			(layer "F.Fab")
			(hide yes)
			(effects
				(font
					(size 1 1)
					(thickness 0.15)
				)
			)
		)
		(sheetname "/CSI/")
		(sheetfile "csi.kicad_sch")
		(attr smd)
		(fp_poly
			(pts
				(xy -0.925 -0.47) (xy -0.925 0.47) (xy 0.925 0.47) (xy 0.925 -0.47)
			)
			(stroke
				(width 0.05)
				(type default)
			)
			(fill no)
			(layer "F.CrtYd")
		)
		(fp_poly
			(pts
				(xy -0.5 -0.25) (xy -0.5 0.25) (xy 0.5 0.25) (xy 0.5 -0.25)
			)
			(stroke
				(width 0.15)
				(type solid)
			)
			(fill no)
			(layer "F.Fab")
		)
		(fp_text user "${REFERENCE}"
			(at -0.95 3.168 0)
			(layer "F.Fab")
			(effects
				(font
					(size 0.7 0.7)
					(thickness 0.15)
				)
				(justify left bottom)
			)
		)
		(fp_text user "License: Apache-2.0"
			(at -0.949999 5.169 0)
			(layer "F.Fab")
			(effects
				(font
					(size 0.7 0.7)
					(thickness 0.15)
				)
				(justify left bottom)
			)
		)
		(fp_text user "Author: Antmicro"
			(at -0.95 4.169 0)
			(layer "F.Fab")
			(effects
				(font
					(size 0.7 0.7)
					(thickness 0.15)
				)
				(justify left bottom)
			)
		)
		(pad "1" smd roundrect
			(at -0.48 0)
			(size 0.59 0.64)
			(layers "F.Cu" "F.Mask" "F.Paste")
			(roundrect_rratio 0.25)
			(net 1 "GND")
			(pintype "passive")
		)
		(pad "2" smd roundrect
			(at 0.48 0)
			(size 0.59 0.64)
			(layers "F.Cu" "F.Mask" "F.Paste")
			(roundrect_rratio 0.25)
			(net 980 "/CSI/I2C_MUX_A0")
			(pintype "passive")
		)
	)
	(footprint "antmicro-footprints:XDFN-2_1x0.60mm"
		(layer "F.Cu")
		(at 187.3 61 90)
		(property "Reference" "D38"
			(at -0.651 -0.25 90)
			(layer "F.SilkS")
			(effects
				(font
					(size 0.7 0.7)
					(thickness 0.15)
				)
				(justify right top)
			)
		)
		(property "Value" "TPD1E0B04_XDFN-2"
			(at 0 1.5 90)
			(layer "F.Fab")
			(effects
				(font
					(size 0.7 0.7)
					(thickness 0.15)
				)
				(justify left bottom)
			)
		)
		(property "Datasheet" "https://www.ti.com/general/docs/suppproductinfo.tsp?distId=26&gotoUrl=https://www.ti.com/lit/gpn/tpd1e0b04"
			(at 0 0 90)
			(layer "F.Fab")
			(hide yes)
			(effects
				(font
					(size 1.27 1.27)
					(thickness 0.15)
				)
			)
		)
		(property "Description" "Bidirectional TVS, 8 kV,  XDFN-2, 3.6 V, 0.18 pF"
			(at 0 0 90)
			(layer "F.Fab")
			(hide yes)
			(effects
				(font
					(size 1.27 1.27)
					(thickness 0.15)
				)
			)
		)
		(property "MPN" "TPD1E0B04DPYR"
			(at 0 0 90)
			(layer "F.Fab")
			(hide yes)
			(effects
				(font
					(size 1.27 1.27)
					(thickness 0.15)
				)
			)
		)
		(property "Manufacturer" "Texas Instruments"
			(at 0 0 90)
			(layer "F.Fab")
			(hide yes)
			(effects
				(font
					(size 1.27 1.27)
					(thickness 0.15)
				)
			)
		)
		(property "Author" "Antmicro"
			(at 0 0 90)
			(unlocked yes)
			(layer "F.Fab")
			(hide yes)
			(effects
				(font
					(size 1 1)
					(thickness 0.15)
				)
			)
		)
		(property "License" "Apache-2.0"
			(at 0 0 90)
			(unlocked yes)
			(layer "F.Fab")
			(hide yes)
			(effects
				(font
					(size 1 1)
					(thickness 0.15)
				)
			)
		)
		(sheetname "/Peripherals/")
		(sheetfile "peripherals.kicad_sch")
		(attr smd)
		(fp_poly
			(pts
				(xy -0.725 -0.475) (xy 0.725 -0.475) (xy 0.725 0.475) (xy -0.725 0.475)
			)
			(stroke
				(width 0.05)
				(type solid)
			)
			(fill no)
			(layer "F.CrtYd")
		)
		(fp_poly
			(pts
				(xy -0.55 -0.35) (xy 0.55 -0.35) (xy 0.55 0.35) (xy -0.55 0.35)
			)
			(stroke
				(width 0.15)
				(type solid)
			)
			(fill no)
			(layer "F.Fab")
		)
		(fp_text user "${REFERENCE}"
			(at -0.8 3.2 90)
			(layer "F.Fab")
			(effects
				(font
					(size 0.7 0.7)
					(thickness 0.15)
				)
				(justify left bottom)
			)
		)
		(fp_text user "License: Apache-2.0"
			(at -0.799999 5.6 90)
			(layer "F.Fab")
			(effects
				(font
					(size 0.7 0.7)
					(thickness 0.15)
				)
				(justify left bottom)
			)
		)
		(fp_text user "Author: Antmicro"
			(at -0.8 4.4 90)
			(layer "F.Fab")
			(effects
				(font
					(size 0.7 0.7)
					(thickness 0.15)
				)
				(justify left bottom)
			)
		)
		(pad "1" smd roundrect
			(at -0.350999 0 90)
			(size 0.3 0.5)
			(layers "F.Cu" "F.Mask" "F.Paste")
			(roundrect_rratio 0.25)
			(net 1 "GND")
			(pinfunction "C")
			(pintype "passive")
		)
		(pad "2" smd roundrect
			(at 0.349 0 90)
			(size 0.3 0.5)
			(layers "F.Cu" "F.Mask" "F.Paste")
			(roundrect_rratio 0.25)
			(net 356 "/Expansion connector/GPIO.USER_BTN1")
			(pinfunction "A")
			(pintype "passive")
		)
	)
)
